(kicad_pcb
	(version 20260206)
	(generator "pcbnew")
	(generator_version "10.0")
	(general
		(thickness 1.6)
		(legacy_teardrops no)
	)
	(paper "A4")
	(title_block
		(title "9054_F0T_PDB_BD_GPU_F_V04_1213_1550_OCP.brd")
		(comment 1 "Grand Teton / footprints 183-189 of 608")
	)
	(layers
		(0 "F.Cu" signal "TOP")
		(4 "In1.Cu" signal "GND")
		(6 "In2.Cu" signal "IN1")
		(8 "In3.Cu" signal "GND1")
		(10 "In4.Cu" signal "VCC")
		(12 "In5.Cu" signal "VCC1")
		(14 "In6.Cu" signal "GND2")
		(16 "In7.Cu" signal "IN2")
		(18 "In8.Cu" signal "GND3")
		(2 "B.Cu" signal "BOTTOM")
		(9 "F.Adhes" user "F.Adhesive")
		(11 "B.Adhes" user "B.Adhesive")
		(13 "F.Paste" user "Package Geometry/Pastemask Top")
		(15 "B.Paste" user "Package Geometry/Pastemask Bottom")
		(5 "F.SilkS" user "Ref Des/Silkscreen Top")
		(7 "B.SilkS" user "Ref Des/Silkscreen Bottom")
		(1 "F.Mask" user "Board Geometry/Soldermask Top")
		(3 "B.Mask" user "Board Geometry/Soldermask Bottom")
		(17 "Dwgs.User" user "User.Drawings")
		(19 "Cmts.User" user "User.Comments")
		(21 "Eco1.User" user "User.Eco1")
		(23 "Eco2.User" user "User.Eco2")
		(25 "Edge.Cuts" user "Board Geometry/Outline")
		(27 "Margin" user)
		(31 "F.CrtYd" user "Package Geometry/Place Bound Top")
		(29 "B.CrtYd" user "Package Geometry/Place Bound Bottom")
		(35 "F.Fab" user "Ref Des/Assembly Top")
		(33 "B.Fab" user "Ref Des/Assembly Bottom")
	)
	(footprint ""
		(layer "F.Cu")
		(at 278.6634 -76.327)
		(property "Reference" "PR93"
			(at 0 0 0)
			(layer "F.SilkS")
			(hide yes)
			(effects
				(font
					(size 1.27 1.27)
				)
			)
		)
		(property "Value" ""
			(at 0 0 0)
			(layer "F.Fab")
			(effects
				(font
					(size 1.27 1.27)
				)
			)
		)
		(duplicate_pad_numbers_are_jumpers no)
		(fp_line
			(start -0.7874 -0.4064)
			(end 0.7874 -0.4064)
			(stroke
				(width 0.1524)
				(type default)
			)
			(layer "F.SilkS")
		)
		(fp_line
			(start -0.7874 0.4064)
			(end -0.7874 -0.4064)
			(stroke
				(width 0.1524)
				(type default)
			)
			(layer "F.SilkS")
		)
		(fp_line
			(start 0.7874 -0.4064)
			(end 0.7874 0.4064)
			(stroke
				(width 0.1524)
				(type default)
			)
			(layer "F.SilkS")
		)
		(fp_line
			(start 0.7874 0.4064)
			(end -0.7874 0.4064)
			(stroke
				(width 0.1524)
				(type default)
			)
			(layer "F.SilkS")
		)
		(fp_line
			(start -0.67945 -0.305054)
			(end -0.12065 -0.305054)
			(stroke
				(width 0.1)
				(type default)
			)
			(layer "F.Fab")
		)
		(fp_line
			(start -0.67945 0.3048)
			(end -0.67945 -0.305054)
			(stroke
				(width 0.1)
				(type default)
			)
			(layer "F.Fab")
		)
		(fp_line
			(start -0.12065 -0.305054)
			(end -0.12065 -0.2794)
			(stroke
				(width 0.1)
				(type default)
			)
			(layer "F.Fab")
		)
		(fp_line
			(start -0.12065 -0.2794)
			(end 0.12065 -0.2794)
			(stroke
				(width 0.1)
				(type default)
			)
			(layer "F.Fab")
		)
		(fp_line
			(start -0.12065 0.2794)
			(end -0.12065 0.3048)
			(stroke
				(width 0.1)
				(type default)
			)
			(layer "F.Fab")
		)
		(fp_line
			(start -0.12065 0.3048)
			(end -0.67945 0.3048)
			(stroke
				(width 0.1)
				(type default)
			)
			(layer "F.Fab")
		)
		(fp_line
			(start 0.120396 0.2794)
			(end -0.12065 0.2794)
			(stroke
				(width 0.1)
				(type default)
			)
			(layer "F.Fab")
		)
		(fp_line
			(start 0.120396 0.3048)
			(end 0.120396 0.2794)
			(stroke
				(width 0.1)
				(type default)
			)
			(layer "F.Fab")
		)
		(fp_line
			(start 0.12065 -0.3048)
			(end 0.67945 -0.3048)
			(stroke
				(width 0.1)
				(type default)
			)
			(layer "F.Fab")
		)
		(fp_line
			(start 0.12065 -0.2794)
			(end 0.12065 -0.3048)
			(stroke
				(width 0.1)
				(type default)
			)
			(layer "F.Fab")
		)
		(fp_line
			(start 0.67945 -0.3048)
			(end 0.67945 0.3048)
			(stroke
				(width 0.1)
				(type default)
			)
			(layer "F.Fab")
		)
		(fp_line
			(start 0.67945 0.3048)
			(end 0.120396 0.3048)
			(stroke
				(width 0.1)
				(type default)
			)
			(layer "F.Fab")
		)
		(pad "1" smd circle
			(at -0.40005 0)
			(size 0 0)
			(layers "F.Cu" "F.Mask" "F.Paste")
			(net "P52V_HS1_ESTART_R")
		)
		(pad "2" smd circle
			(at 0.40005 0)
			(size 0 0)
			(layers "F.Cu" "F.Mask" "F.Paste")
			(net "P52V_HS1_ESTART")
		)
	)
	(footprint ""
		(layer "F.Cu")
		(at 449.326 -32.893 180)
		(property "Reference" "R19"
			(at 0 0 180)
			(layer "F.SilkS")
			(hide yes)
			(effects
				(font
					(size 1.27 1.27)
				)
			)
		)
		(property "Value" ""
			(at 0 0 180)
			(layer "F.Fab")
			(effects
				(font
					(size 1.27 1.27)
				)
			)
		)
		(duplicate_pad_numbers_are_jumpers no)
		(fp_line
			(start 0.7874 0.4064)
			(end -0.7874 0.4064)
			(stroke
				(width 0.1524)
				(type default)
			)
			(layer "F.SilkS")
		)
		(fp_line
			(start 0.7874 -0.4064)
			(end 0.7874 0.4064)
			(stroke
				(width 0.1524)
				(type default)
			)
			(layer "F.SilkS")
		)
		(fp_line
			(start -0.7874 0.4064)
			(end -0.7874 -0.4064)
			(stroke
				(width 0.1524)
				(type default)
			)
			(layer "F.SilkS")
		)
		(fp_line
			(start -0.7874 -0.4064)
			(end 0.7874 -0.4064)
			(stroke
				(width 0.1524)
				(type default)
			)
			(layer "F.SilkS")
		)
		(fp_line
			(start 0.67945 0.3048)
			(end 0.120396 0.3048)
			(stroke
				(width 0.1)
				(type default)
			)
			(layer "F.Fab")
		)
		(fp_line
			(start 0.67945 -0.3048)
			(end 0.67945 0.3048)
			(stroke
				(width 0.1)
				(type default)
			)
			(layer "F.Fab")
		)
		(fp_line
			(start 0.12065 -0.2794)
			(end 0.12065 -0.3048)
			(stroke
				(width 0.1)
				(type default)
			)
			(layer "F.Fab")
		)
		(fp_line
			(start 0.12065 -0.3048)
			(end 0.67945 -0.3048)
			(stroke
				(width 0.1)
				(type default)
			)
			(layer "F.Fab")
		)
		(fp_line
			(start 0.120396 0.3048)
			(end 0.120396 0.2794)
			(stroke
				(width 0.1)
				(type default)
			)
			(layer "F.Fab")
		)
		(fp_line
			(start 0.120396 0.2794)
			(end -0.12065 0.2794)
			(stroke
				(width 0.1)
				(type default)
			)
			(layer "F.Fab")
		)
		(fp_line
			(start -0.12065 0.3048)
			(end -0.67945 0.3048)
			(stroke
				(width 0.1)
				(type default)
			)
			(layer "F.Fab")
		)
		(fp_line
			(start -0.12065 0.2794)
			(end -0.12065 0.3048)
			(stroke
				(width 0.1)
				(type default)
			)
			(layer "F.Fab")
		)
		(fp_line
			(start -0.12065 -0.2794)
			(end 0.12065 -0.2794)
			(stroke
				(width 0.1)
				(type default)
			)
			(layer "F.Fab")
		)
		(fp_line
			(start -0.12065 -0.305054)
			(end -0.12065 -0.2794)
			(stroke
				(width 0.1)
				(type default)
			)
			(layer "F.Fab")
		)
		(fp_line
			(start -0.67945 0.3048)
			(end -0.67945 -0.305054)
			(stroke
				(width 0.1)
				(type default)
			)
			(layer "F.Fab")
		)
		(fp_line
			(start -0.67945 -0.305054)
			(end -0.12065 -0.305054)
			(stroke
				(width 0.1)
				(type default)
			)
			(layer "F.Fab")
		)
		(pad "1" smd circle
			(at -0.40005 0 180)
			(size 0 0)
			(layers "F.Cu" "F.Mask" "F.Paste")
			(net "SMB_PDB_MISC_SDA")
		)
		(pad "2" smd circle
			(at 0.40005 0 180)
			(size 0 0)
			(layers "F.Cu" "F.Mask" "F.Paste")
			(net "SMB_FAN_MUX_SDA")
		)
	)
	(footprint ""
		(layer "F.Cu")
		(at 250.000008 -16.500094 180)
		(property "Reference" "H9"
			(at 0.572008 -5.350764 0)
			(unlocked yes)
			(layer "F.SilkS")
			(effects
				(font
					(size 0.7874 0.5842)
					(thickness 0.1524)
				)
				(justify left)
			)
		)
		(property "Value" ""
			(at 0 0 180)
			(layer "F.Fab")
			(effects
				(font
					(size 1.27 1.27)
				)
			)
		)
		(duplicate_pad_numbers_are_jumpers no)
		(pad "1" thru_hole oval
			(at 0 0 180)
			(size 9.017 14.0208)
			(drill 3.0226
				(offset 0 2.499868)
			)
			(layers "*.Cu" "*.Mask")
			(remove_unused_layers no)
			(net "GND")
			(clearance -1.500378)
			(padstack
				(mode front_inner_back)
				(layer "Inner"
					(shape circle)
					(size 0 0)
					(clearance 0)
				)
				(layer "B.Cu"
					(shape oval)
					(size 9.017 14.0208)
					(offset 0 2.499868)
					(clearance -1.500378)
				)
			)
		)
	)
	(footprint ""
		(layer "F.Cu")
		(at 439.674 -61.849 -90)
		(property "Reference" "D6"
			(at 2.9718 -0.03937 90)
			(unlocked yes)
			(layer "F.SilkS")
			(effects
				(font
					(size 0.7874 0.5842)
					(thickness 0.1524)
				)
				(justify left)
			)
		)
		(property "Value" ""
			(at 0 0 270)
			(layer "F.Fab")
			(effects
				(font
					(size 1.27 1.27)
				)
			)
		)
		(duplicate_pad_numbers_are_jumpers no)
		(fp_line
			(start -0.90678 0.4826)
			(end -0.90678 -0.4699)
			(stroke
				(width 0.1524)
				(type default)
			)
			(layer "F.SilkS")
		)
		(fp_line
			(start 0.90678 0.4826)
			(end -0.90678 0.4826)
			(stroke
				(width 0.1524)
				(type default)
			)
			(layer "F.SilkS")
		)
		(fp_line
			(start 1.03378 0.4826)
			(end -0.79248 0.4826)
			(stroke
				(width 0.1524)
				(type default)
			)
			(layer "F.SilkS")
		)
		(fp_line
			(start 1.16078 0.4826)
			(end -0.64008 0.4826)
			(stroke
				(width 0.1524)
				(type default)
			)
			(layer "F.SilkS")
		)
		(fp_line
			(start -0.89408 -0.4826)
			(end 0.90678 -0.4826)
			(stroke
				(width 0.1524)
				(type default)
			)
			(layer "F.SilkS")
		)
		(fp_line
			(start -0.79248 -0.4826)
			(end 1.03378 -0.4826)
			(stroke
				(width 0.1524)
				(type default)
			)
			(layer "F.SilkS")
		)
		(fp_line
			(start -0.64008 -0.4826)
			(end 1.16078 -0.4826)
			(stroke
				(width 0.1524)
				(type default)
			)
			(layer "F.SilkS")
		)
		(fp_line
			(start 0.90678 -0.4826)
			(end 0.90678 0.4826)
			(stroke
				(width 0.1524)
				(type default)
			)
			(layer "F.SilkS")
		)
		(fp_line
			(start 1.03378 -0.4826)
			(end 1.03378 0.4826)
			(stroke
				(width 0.1524)
				(type default)
			)
			(layer "F.SilkS")
		)
		(fp_line
			(start 1.16078 -0.4826)
			(end 1.16078 0.4826)
			(stroke
				(width 0.1524)
				(type default)
			)
			(layer "F.SilkS")
		)
		(fp_line
			(start -0.499872 0.249936)
			(end -0.499872 -0.249936)
			(stroke
				(width 0.1)
				(type default)
			)
			(layer "F.Fab")
		)
		(fp_line
			(start 0.499872 0.249936)
			(end -0.499872 0.249936)
			(stroke
				(width 0.1)
				(type default)
			)
			(layer "F.Fab")
		)
		(fp_line
			(start -0.499872 -0.249936)
			(end 0.499872 -0.249936)
			(stroke
				(width 0.1)
				(type default)
			)
			(layer "F.Fab")
		)
		(fp_line
			(start 0.499872 -0.249936)
			(end 0.499872 0.249936)
			(stroke
				(width 0.1)
				(type default)
			)
			(layer "F.Fab")
		)
		(pad "A" smd rect
			(at -0.47498 0 270)
			(size 0.6096 0.7112)
			(layers "F.Cu" "F.Mask" "F.Paste")
			(net "LED_D6_R1")
		)
		(pad "C" smd rect
			(at 0.47498 0 270)
			(size 0.6096 0.7112)
			(layers "F.Cu" "F.Mask" "F.Paste")
			(net "GND")
		)
	)
	(footprint ""
		(layer "F.Cu")
		(at 433.6288 -41.148 90)
		(property "Reference" "R389"
			(at 0 0 90)
			(layer "F.SilkS")
			(hide yes)
			(effects
				(font
					(size 1.27 1.27)
				)
			)
		)
		(property "Value" ""
			(at 0 0 90)
			(layer "F.Fab")
			(effects
				(font
					(size 1.27 1.27)
				)
			)
		)
		(duplicate_pad_numbers_are_jumpers no)
		(fp_line
			(start 0.7874 -0.4064)
			(end 0.7874 0.4064)
			(stroke
				(width 0.1524)
				(type default)
			)
			(layer "F.SilkS")
		)
		(fp_line
			(start -0.7874 -0.4064)
			(end 0.7874 -0.4064)
			(stroke
				(width 0.1524)
				(type default)
			)
			(layer "F.SilkS")
		)
		(fp_line
			(start 0.7874 0.4064)
			(end -0.7874 0.4064)
			(stroke
				(width 0.1524)
				(type default)
			)
			(layer "F.SilkS")
		)
		(fp_line
			(start -0.7874 0.4064)
			(end -0.7874 -0.4064)
			(stroke
				(width 0.1524)
				(type default)
			)
			(layer "F.SilkS")
		)
		(fp_line
			(start -0.12065 -0.305054)
			(end -0.12065 -0.2794)
			(stroke
				(width 0.1)
				(type default)
			)
			(layer "F.Fab")
		)
		(fp_line
			(start -0.67945 -0.305054)
			(end -0.12065 -0.305054)
			(stroke
				(width 0.1)
				(type default)
			)
			(layer "F.Fab")
		)
		(fp_line
			(start 0.67945 -0.3048)
			(end 0.67945 0.3048)
			(stroke
				(width 0.1)
				(type default)
			)
			(layer "F.Fab")
		)
		(fp_line
			(start 0.12065 -0.3048)
			(end 0.67945 -0.3048)
			(stroke
				(width 0.1)
				(type default)
			)
			(layer "F.Fab")
		)
		(fp_line
			(start 0.12065 -0.2794)
			(end 0.12065 -0.3048)
			(stroke
				(width 0.1)
				(type default)
			)
			(layer "F.Fab")
		)
		(fp_line
			(start -0.12065 -0.2794)
			(end 0.12065 -0.2794)
			(stroke
				(width 0.1)
				(type default)
			)
			(layer "F.Fab")
		)
		(fp_line
			(start 0.120396 0.2794)
			(end -0.12065 0.2794)
			(stroke
				(width 0.1)
				(type default)
			)
			(layer "F.Fab")
		)
		(fp_line
			(start -0.12065 0.2794)
			(end -0.12065 0.3048)
			(stroke
				(width 0.1)
				(type default)
			)
			(layer "F.Fab")
		)
		(fp_line
			(start 0.67945 0.3048)
			(end 0.120396 0.3048)
			(stroke
				(width 0.1)
				(type default)
			)
			(layer "F.Fab")
		)
		(fp_line
			(start 0.120396 0.3048)
			(end 0.120396 0.2794)
			(stroke
				(width 0.1)
				(type default)
			)
			(layer "F.Fab")
		)
		(fp_line
			(start -0.12065 0.3048)
			(end -0.67945 0.3048)
			(stroke
				(width 0.1)
				(type default)
			)
			(layer "F.Fab")
		)
		(fp_line
			(start -0.67945 0.3048)
			(end -0.67945 -0.305054)
			(stroke
				(width 0.1)
				(type default)
			)
			(layer "F.Fab")
		)
		(pad "1" smd circle
			(at -0.40005 0 90)
			(size 0 0)
			(layers "F.Cu" "F.Mask" "F.Paste")
			(net "SMB_PDB_MISC_SCL_R1")
		)
		(pad "2" smd circle
			(at 0.40005 0 90)
			(size 0 0)
			(layers "F.Cu" "F.Mask" "F.Paste")
			(net "SMB_PDB_MISC_SCL")
		)
	)
	(footprint ""
		(layer "F.Cu")
		(at 449.3514 -30.607)
		(property "Reference" "R63"
			(at 0 0 0)
			(layer "F.SilkS")
			(hide yes)
			(effects
				(font
					(size 1.27 1.27)
				)
			)
		)
		(property "Value" ""
			(at 0 0 0)
			(layer "F.Fab")
			(effects
				(font
					(size 1.27 1.27)
				)
			)
		)
		(duplicate_pad_numbers_are_jumpers no)
		(fp_line
			(start -0.7874 -0.4064)
			(end 0.7874 -0.4064)
			(stroke
				(width 0.1524)
				(type default)
			)
			(layer "F.SilkS")
		)
		(fp_line
			(start -0.7874 0.4064)
			(end -0.7874 -0.4064)
			(stroke
				(width 0.1524)
				(type default)
			)
			(layer "F.SilkS")
		)
		(fp_line
			(start 0.7874 -0.4064)
			(end 0.7874 0.4064)
			(stroke
				(width 0.1524)
				(type default)
			)
			(layer "F.SilkS")
		)
		(fp_line
			(start 0.7874 0.4064)
			(end -0.7874 0.4064)
			(stroke
				(width 0.1524)
				(type default)
			)
			(layer "F.SilkS")
		)
		(fp_line
			(start -0.67945 -0.305054)
			(end -0.12065 -0.305054)
			(stroke
				(width 0.1)
				(type default)
			)
			(layer "F.Fab")
		)
		(fp_line
			(start -0.67945 0.3048)
			(end -0.67945 -0.305054)
			(stroke
				(width 0.1)
				(type default)
			)
			(layer "F.Fab")
		)
		(fp_line
			(start -0.12065 -0.305054)
			(end -0.12065 -0.2794)
			(stroke
				(width 0.1)
				(type default)
			)
			(layer "F.Fab")
		)
		(fp_line
			(start -0.12065 -0.2794)
			(end 0.12065 -0.2794)
			(stroke
				(width 0.1)
				(type default)
			)
			(layer "F.Fab")
		)
		(fp_line
			(start -0.12065 0.2794)
			(end -0.12065 0.3048)
			(stroke
				(width 0.1)
				(type default)
			)
			(layer "F.Fab")
		)
		(fp_line
			(start -0.12065 0.3048)
			(end -0.67945 0.3048)
			(stroke
				(width 0.1)
				(type default)
			)
			(layer "F.Fab")
		)
		(fp_line
			(start 0.120396 0.2794)
			(end -0.12065 0.2794)
			(stroke
				(width 0.1)
				(type default)
			)
			(layer "F.Fab")
		)
		(fp_line
			(start 0.120396 0.3048)
			(end 0.120396 0.2794)
			(stroke
				(width 0.1)
				(type default)
			)
			(layer "F.Fab")
		)
		(fp_line
			(start 0.12065 -0.3048)
			(end 0.67945 -0.3048)
			(stroke
				(width 0.1)
				(type default)
			)
			(layer "F.Fab")
		)
		(fp_line
			(start 0.12065 -0.2794)
			(end 0.12065 -0.3048)
			(stroke
				(width 0.1)
				(type default)
			)
			(layer "F.Fab")
		)
		(fp_line
			(start 0.67945 -0.3048)
			(end 0.67945 0.3048)
			(stroke
				(width 0.1)
				(type default)
			)
			(layer "F.Fab")
		)
		(fp_line
			(start 0.67945 0.3048)
			(end 0.120396 0.3048)
			(stroke
				(width 0.1)
				(type default)
			)
			(layer "F.Fab")
		)
		(pad "1" smd circle
			(at -0.40005 0)
			(size 0 0)
			(layers "F.Cu" "F.Mask" "F.Paste")
			(net "SMB_FRU_CLK")
		)
		(pad "2" smd circle
			(at 0.40005 0)
			(size 0 0)
			(layers "F.Cu" "F.Mask" "F.Paste")
			(net "SMB_PDB_MISC_SCL_R1")
		)
	)
	(footprint ""
		(layer "F.Cu")
		(at 129.612136 -83.566)
		(property "Reference" "PR6996"
			(at 0 0 0)
			(layer "F.SilkS")
			(hide yes)
			(effects
				(font
					(size 1.27 1.27)
				)
			)
		)
		(property "Value" ""
			(at 0 0 0)
			(layer "F.Fab")
			(effects
				(font
					(size 1.27 1.27)
				)
			)
		)
		(duplicate_pad_numbers_are_jumpers no)
		(fp_line
			(start -0.7874 -0.4064)
			(end 0.7874 -0.4064)
			(stroke
				(width 0.1524)
				(type default)
			)
			(layer "F.SilkS")
		)
		(fp_line
			(start -0.7874 0.4064)
			(end -0.7874 -0.4064)
			(stroke
				(width 0.1524)
				(type default)
			)
			(layer "F.SilkS")
		)
		(fp_line
			(start 0.7874 -0.4064)
			(end 0.7874 0.4064)
			(stroke
				(width 0.1524)
				(type default)
			)
			(layer "F.SilkS")
		)
		(fp_line
			(start 0.7874 0.4064)
			(end -0.7874 0.4064)
			(stroke
				(width 0.1524)
				(type default)
			)
			(layer "F.SilkS")
		)
		(fp_line
			(start -0.67945 -0.305054)
			(end -0.12065 -0.305054)
			(stroke
				(width 0.1)
				(type default)
			)
			(layer "F.Fab")
		)
		(fp_line
			(start -0.67945 0.3048)
			(end -0.67945 -0.305054)
			(stroke
				(width 0.1)
				(type default)
			)
			(layer "F.Fab")
		)
		(fp_line
			(start -0.12065 -0.305054)
			(end -0.12065 -0.2794)
			(stroke
				(width 0.1)
				(type default)
			)
			(layer "F.Fab")
		)
		(fp_line
			(start -0.12065 -0.2794)
			(end 0.12065 -0.2794)
			(stroke
				(width 0.1)
				(type default)
			)
			(layer "F.Fab")
		)
		(fp_line
			(start -0.12065 0.2794)
			(end -0.12065 0.3048)
			(stroke
				(width 0.1)
				(type default)
			)
			(layer "F.Fab")
		)
		(fp_line
			(start -0.12065 0.3048)
			(end -0.67945 0.3048)
			(stroke
				(width 0.1)
				(type default)
			)
			(layer "F.Fab")
		)
		(fp_line
			(start 0.120396 0.2794)
			(end -0.12065 0.2794)
			(stroke
				(width 0.1)
				(type default)
			)
			(layer "F.Fab")
		)
		(fp_line
			(start 0.120396 0.3048)
			(end 0.120396 0.2794)
			(stroke
				(width 0.1)
				(type default)
			)
			(layer "F.Fab")
		)
		(fp_line
			(start 0.12065 -0.3048)
			(end 0.67945 -0.3048)
			(stroke
				(width 0.1)
				(type default)
			)
			(layer "F.Fab")
		)
		(fp_line
			(start 0.12065 -0.2794)
			(end 0.12065 -0.3048)
			(stroke
				(width 0.1)
				(type default)
			)
			(layer "F.Fab")
		)
		(fp_line
			(start 0.67945 -0.3048)
			(end 0.67945 0.3048)
			(stroke
				(width 0.1)
				(type default)
			)
			(layer "F.Fab")
		)
		(fp_line
			(start 0.67945 0.3048)
			(end 0.120396 0.3048)
			(stroke
				(width 0.1)
				(type default)
			)
			(layer "F.Fab")
		)
		(pad "1" smd rect
			(at -0.40005 0 180)
			(size 0.4572 0.508)
			(layers "F.Cu" "F.Mask" "F.Paste")
			(net "P52V_HS2_TEMPN")
		)
		(pad "2" smd rect
			(at 0.40005 0 180)
			(size 0.4572 0.508)
			(layers "F.Cu" "F.Mask" "F.Paste")
			(net "P52V_HS2_TEMPN_R")
		)
	)
)
